(kicad_pcb
	(version 20260206)
	(generator "pcbnew")
	(generator_version "10.0")
	(general
		(thickness 1.6)
		(legacy_teardrops no)
	)
	(paper "A4")
	(title_block
		(title "v1-chassis-manager — T6M_CM_d_v01_1031_1645.brd")
		(comment 1 "Open CloudServer (Microsoft) / footprints 1242-1251 of 2512")
	)
	(layers
		(0 "F.Cu" signal "TOP")
		(4 "In1.Cu" signal "GND1")
		(6 "In2.Cu" signal "IN1")
		(8 "In3.Cu" signal "VCC1")
		(10 "In4.Cu" signal "VCC2")
		(12 "In5.Cu" signal "GND2")
		(14 "In6.Cu" signal "IN2")
		(16 "In7.Cu" signal "IN3")
		(18 "In8.Cu" signal "GND3")
		(2 "B.Cu" signal "BOTTOM")
		(9 "F.Adhes" user "F.Adhesive")
		(11 "B.Adhes" user "B.Adhesive")
		(13 "F.Paste" user "Package Geometry/Pastemask Top")
		(15 "B.Paste" user "Package Geometry/Pastemask Bottom")
		(5 "F.SilkS" user "Ref Des/Silkscreen Top")
		(7 "B.SilkS" user "Ref Des/Silkscreen Bottom")
		(1 "F.Mask" user "Board Geometry/Soldermask Top")
		(3 "B.Mask" user "Board Geometry/Soldermask Bottom")
		(17 "Dwgs.User" user "User.Drawings")
		(19 "Cmts.User" user "User.Comments")
		(21 "Eco1.User" user "User.Eco1")
		(23 "Eco2.User" user "User.Eco2")
		(25 "Edge.Cuts" user "Board Geometry/Outline")
		(27 "Margin" user)
		(31 "F.CrtYd" user "Package Geometry/Place Bound Top")
		(29 "B.CrtYd" user "Package Geometry/Place Bound Bottom")
		(35 "F.Fab" user "Ref Des/Assembly Top")
		(33 "B.Fab" user "Ref Des/Assembly Bottom")
	)
	(footprint ""
		(layer "F.Cu")
		(at 64.899286 -118.758462 90)
		(property "Reference" "R338"
			(at -4.988306 -0.717042 90)
			(unlocked yes)
			(layer "F.SilkS")
			(effects
				(font
					(size 0.7874 0.5842)
					(thickness 0.1524)
				)
				(justify left)
			)
		)
		(property "Value" ""
			(at 0 0 90)
			(layer "F.Fab")
			(effects
				(font
					(size 1.27 1.27)
				)
			)
		)
		(duplicate_pad_numbers_are_jumpers no)
		(fp_line
			(start 0.7874 -0.4064)
			(end 0.7874 0.4064)
			(stroke
				(width 0.1524)
				(type default)
			)
			(layer "F.SilkS")
		)
		(fp_line
			(start -0.7874 -0.4064)
			(end 0.7874 -0.4064)
			(stroke
				(width 0.1524)
				(type default)
			)
			(layer "F.SilkS")
		)
		(fp_line
			(start 0.7874 0.4064)
			(end -0.7874 0.4064)
			(stroke
				(width 0.1524)
				(type default)
			)
			(layer "F.SilkS")
		)
		(fp_line
			(start -0.7874 0.4064)
			(end -0.7874 -0.4064)
			(stroke
				(width 0.1524)
				(type default)
			)
			(layer "F.SilkS")
		)
		(fp_poly
			(pts
				(xy -0.508 0.2794) (xy -0.508 0.2286) (xy -0.635 0.2286) (xy -0.635 -0.254) (xy -0.5334 -0.254)
				(xy -0.5334 -0.2794) (xy 0.5334 -0.2794) (xy 0.5334 -0.254) (xy 0.635 -0.254) (xy 0.635 0.254) (xy 0.5334 0.254)
				(xy 0.5334 0.2794)
			)
			(stroke
				(width 0)
				(type default)
			)
			(fill no)
			(layer "F.CrtYd")
		)
		(pad "1" smd rect
			(at 0.40005 0 90)
			(size 0.4572 0.508)
			(layers "F.Cu" "F.Mask" "F.Paste")
			(net "P3V3_NODE1")
		)
		(pad "2" smd rect
			(at -0.40005 0 90)
			(size 0.4572 0.508)
			(layers "F.Cu" "F.Mask" "F.Paste")
			(net "BMC_ROMA22")
		)
	)
	(footprint ""
		(layer "F.Cu")
		(at 109.766608 -142.410942 90)
		(property "Reference" "PR61"
			(at 1.927352 0.092964 90)
			(unlocked yes)
			(layer "F.SilkS")
			(effects
				(font
					(size 0.635 0.4064)
					(thickness 0.1524)
				)
				(justify left)
			)
		)
		(property "Value" ""
			(at 0 0 90)
			(layer "F.Fab")
			(effects
				(font
					(size 1.27 1.27)
				)
			)
		)
		(duplicate_pad_numbers_are_jumpers no)
		(fp_line
			(start 0.7874 -0.4064)
			(end 0.7874 0.4064)
			(stroke
				(width 0.1524)
				(type default)
			)
			(layer "F.SilkS")
		)
		(fp_line
			(start -0.7874 -0.4064)
			(end 0.7874 -0.4064)
			(stroke
				(width 0.1524)
				(type default)
			)
			(layer "F.SilkS")
		)
		(fp_line
			(start 0.7874 0.4064)
			(end -0.7874 0.4064)
			(stroke
				(width 0.1524)
				(type default)
			)
			(layer "F.SilkS")
		)
		(fp_line
			(start -0.7874 0.4064)
			(end -0.7874 -0.4064)
			(stroke
				(width 0.1524)
				(type default)
			)
			(layer "F.SilkS")
		)
		(fp_poly
			(pts
				(xy -0.508 0.2794) (xy -0.508 0.2286) (xy -0.635 0.2286) (xy -0.635 -0.254) (xy -0.5334 -0.254)
				(xy -0.5334 -0.2794) (xy 0.5334 -0.2794) (xy 0.5334 -0.254) (xy 0.635 -0.254) (xy 0.635 0.254) (xy 0.5334 0.254)
				(xy 0.5334 0.2794)
			)
			(stroke
				(width 0)
				(type default)
			)
			(fill no)
			(layer "F.CrtYd")
		)
		(pad "1" smd rect
			(at 0.40005 0 90)
			(size 0.4572 0.508)
			(layers "F.Cu" "F.Mask" "F.Paste")
			(net "VR_PVCCP_NODE1_VCC")
		)
		(pad "2" smd rect
			(at -0.40005 0 90)
			(size 0.4572 0.508)
			(layers "F.Cu" "F.Mask" "F.Paste")
			(net "VR_PVCCP_NODE1_TEMPMAX")
		)
	)
	(footprint ""
		(layer "F.Cu")
		(at 83.472782 -89.865454)
		(property "Reference" "R138"
			(at -1.36017 -1.038606 0)
			(unlocked yes)
			(layer "F.SilkS")
			(effects
				(font
					(size 0.635 0.4064)
					(thickness 0.1524)
				)
				(justify left)
			)
		)
		(property "Value" ""
			(at 0 0 0)
			(layer "F.Fab")
			(effects
				(font
					(size 1.27 1.27)
				)
			)
		)
		(duplicate_pad_numbers_are_jumpers no)
		(fp_line
			(start -0.7874 -0.4064)
			(end 0.7874 -0.4064)
			(stroke
				(width 0.1524)
				(type default)
			)
			(layer "F.SilkS")
		)
		(fp_line
			(start -0.7874 0.4064)
			(end -0.7874 -0.4064)
			(stroke
				(width 0.1524)
				(type default)
			)
			(layer "F.SilkS")
		)
		(fp_line
			(start 0.7874 -0.4064)
			(end 0.7874 0.4064)
			(stroke
				(width 0.1524)
				(type default)
			)
			(layer "F.SilkS")
		)
		(fp_line
			(start 0.7874 0.4064)
			(end -0.7874 0.4064)
			(stroke
				(width 0.1524)
				(type default)
			)
			(layer "F.SilkS")
		)
		(fp_poly
			(pts
				(xy -0.508 0.2794) (xy -0.508 0.2286) (xy -0.635 0.2286) (xy -0.635 -0.254) (xy -0.5334 -0.254)
				(xy -0.5334 -0.2794) (xy 0.5334 -0.2794) (xy 0.5334 -0.254) (xy 0.635 -0.254) (xy 0.635 0.254) (xy 0.5334 0.254)
				(xy 0.5334 0.2794)
			)
			(stroke
				(width 0)
				(type default)
			)
			(fill no)
			(layer "F.CrtYd")
		)
		(pad "1" smd rect
			(at 0.40005 0)
			(size 0.4572 0.508)
			(layers "F.Cu" "F.Mask" "F.Paste")
			(net "P3V3_SUS_NODE1")
		)
		(pad "2" smd rect
			(at -0.40005 0)
			(size 0.4572 0.508)
			(layers "F.Cu" "F.Mask" "F.Paste")
			(net "FM_CPU_NODE1_RSTRDY_L")
		)
	)
	(footprint ""
		(layer "F.Cu")
		(at 123.372626 -70.572884 90)
		(property "Reference" "R147"
			(at -3.886962 0.577596 90)
			(unlocked yes)
			(layer "F.SilkS")
			(effects
				(font
					(size 0.7874 0.5842)
					(thickness 0.1524)
				)
				(justify left)
			)
		)
		(property "Value" ""
			(at 0 0 90)
			(layer "F.Fab")
			(effects
				(font
					(size 1.27 1.27)
				)
			)
		)
		(duplicate_pad_numbers_are_jumpers no)
		(fp_line
			(start 0.7874 -0.4064)
			(end 0.7874 0.4064)
			(stroke
				(width 0.1524)
				(type default)
			)
			(layer "F.SilkS")
		)
		(fp_line
			(start -0.7874 -0.4064)
			(end 0.7874 -0.4064)
			(stroke
				(width 0.1524)
				(type default)
			)
			(layer "F.SilkS")
		)
		(fp_line
			(start 0.7874 0.4064)
			(end -0.7874 0.4064)
			(stroke
				(width 0.1524)
				(type default)
			)
			(layer "F.SilkS")
		)
		(fp_line
			(start -0.7874 0.4064)
			(end -0.7874 -0.4064)
			(stroke
				(width 0.1524)
				(type default)
			)
			(layer "F.SilkS")
		)
		(fp_poly
			(pts
				(xy -0.508 0.2794) (xy -0.508 0.2286) (xy -0.635 0.2286) (xy -0.635 -0.254) (xy -0.5334 -0.254)
				(xy -0.5334 -0.2794) (xy 0.5334 -0.2794) (xy 0.5334 -0.254) (xy 0.635 -0.254) (xy 0.635 0.254) (xy 0.5334 0.254)
				(xy 0.5334 0.2794)
			)
			(stroke
				(width 0)
				(type default)
			)
			(fill no)
			(layer "F.CrtYd")
		)
		(pad "1" smd rect
			(at 0.40005 0 90)
			(size 0.4572 0.508)
			(layers "F.Cu" "F.Mask" "F.Paste")
			(net "P3V_COIN_CELL")
		)
		(pad "2" smd rect
			(at -0.40005 0 90)
			(size 0.4572 0.508)
			(layers "F.Cu" "F.Mask" "F.Paste")
			(net "P3V0_BAT_NODE1_R")
		)
	)
	(footprint ""
		(layer "F.Cu")
		(at 69.755004 -164.621718 180)
		(property "Reference" "R678"
			(at 4.49072 0.046228 0)
			(unlocked yes)
			(layer "F.SilkS")
			(effects
				(font
					(size 0.7874 0.5842)
					(thickness 0.1524)
				)
				(justify left)
			)
		)
		(property "Value" ""
			(at 0 0 180)
			(layer "F.Fab")
			(effects
				(font
					(size 1.27 1.27)
				)
			)
		)
		(duplicate_pad_numbers_are_jumpers no)
		(fp_line
			(start 0.7874 0.4064)
			(end -0.7874 0.4064)
			(stroke
				(width 0.1524)
				(type default)
			)
			(layer "F.SilkS")
		)
		(fp_line
			(start 0.7874 -0.4064)
			(end 0.7874 0.4064)
			(stroke
				(width 0.1524)
				(type default)
			)
			(layer "F.SilkS")
		)
		(fp_line
			(start -0.7874 0.4064)
			(end -0.7874 -0.4064)
			(stroke
				(width 0.1524)
				(type default)
			)
			(layer "F.SilkS")
		)
		(fp_line
			(start -0.7874 -0.4064)
			(end 0.7874 -0.4064)
			(stroke
				(width 0.1524)
				(type default)
			)
			(layer "F.SilkS")
		)
		(fp_poly
			(pts
				(xy -0.508 0.2794) (xy -0.508 0.2286) (xy -0.635 0.2286) (xy -0.635 -0.254) (xy -0.5334 -0.254)
				(xy -0.5334 -0.2794) (xy 0.5334 -0.2794) (xy 0.5334 -0.254) (xy 0.635 -0.254) (xy 0.635 0.254) (xy 0.5334 0.254)
				(xy 0.5334 0.2794)
			)
			(stroke
				(width 0)
				(type default)
			)
			(fill no)
			(layer "F.CrtYd")
		)
		(pad "1" smd rect
			(at 0.40005 0 180)
			(size 0.4572 0.508)
			(layers "F.Cu" "F.Mask" "F.Paste")
			(net "CPLD123_RSV3")
		)
		(pad "2" smd rect
			(at -0.40005 0 180)
			(size 0.4572 0.508)
			(layers "F.Cu" "F.Mask" "F.Paste")
			(net "CPLD2_RSV3")
		)
	)
	(footprint ""
		(layer "F.Cu")
		(at 131.30657 -26.569416 -90)
		(property "Reference" "R1145"
			(at 5.325618 -0.127508 90)
			(unlocked yes)
			(layer "F.SilkS")
			(effects
				(font
					(size 0.7874 0.5842)
					(thickness 0.1524)
				)
				(justify left)
			)
		)
		(property "Value" ""
			(at 0 0 270)
			(layer "F.Fab")
			(effects
				(font
					(size 1.27 1.27)
				)
			)
		)
		(duplicate_pad_numbers_are_jumpers no)
		(fp_line
			(start -0.7874 0.4064)
			(end -0.7874 -0.4064)
			(stroke
				(width 0.1524)
				(type default)
			)
			(layer "F.SilkS")
		)
		(fp_line
			(start 0.7874 0.4064)
			(end -0.7874 0.4064)
			(stroke
				(width 0.1524)
				(type default)
			)
			(layer "F.SilkS")
		)
		(fp_line
			(start -0.7874 -0.4064)
			(end 0.7874 -0.4064)
			(stroke
				(width 0.1524)
				(type default)
			)
			(layer "F.SilkS")
		)
		(fp_line
			(start 0.7874 -0.4064)
			(end 0.7874 0.4064)
			(stroke
				(width 0.1524)
				(type default)
			)
			(layer "F.SilkS")
		)
		(fp_poly
			(pts
				(xy -0.508 0.2794) (xy -0.508 0.2286) (xy -0.635 0.2286) (xy -0.635 -0.254) (xy -0.5334 -0.254)
				(xy -0.5334 -0.2794) (xy 0.5334 -0.2794) (xy 0.5334 -0.254) (xy 0.635 -0.254) (xy 0.635 0.254) (xy 0.5334 0.254)
				(xy 0.5334 0.2794)
			)
			(stroke
				(width 0)
				(type default)
			)
			(fill no)
			(layer "F.CrtYd")
		)
		(pad "1" smd rect
			(at 0.40005 0 270)
			(size 0.4572 0.508)
			(layers "F.Cu" "F.Mask" "F.Paste")
			(net "P3V3_STB_NODE1")
		)
		(pad "2" smd rect
			(at -0.40005 0 270)
			(size 0.4572 0.508)
			(layers "F.Cu" "F.Mask" "F.Paste")
			(net "SIO_PIN80")
		)
	)
	(footprint ""
		(layer "F.Cu")
		(at 122.03176 -179.363624 -90)
		(property "Reference" "D15"
			(at -3.39344 -5.986272 90)
			(unlocked yes)
			(layer "F.SilkS")
			(effects
				(font
					(size 0.635 0.4064)
					(thickness 0.1524)
				)
				(justify left)
			)
		)
		(property "Value" ""
			(at 0 0 270)
			(layer "F.Fab")
			(effects
				(font
					(size 1.27 1.27)
				)
			)
		)
		(duplicate_pad_numbers_are_jumpers no)
		(fp_line
			(start -1.3208 0.5588)
			(end -1.3208 -0.5588)
			(stroke
				(width 0.1524)
				(type default)
			)
			(layer "F.SilkS")
		)
		(fp_line
			(start 1.3208 0.5588)
			(end -1.3208 0.5588)
			(stroke
				(width 0.1524)
				(type default)
			)
			(layer "F.SilkS")
		)
		(fp_line
			(start 1.6256 0.5588)
			(end 1.6256 -0.5588)
			(stroke
				(width 0.1524)
				(type default)
			)
			(layer "F.SilkS")
		)
		(fp_line
			(start 1.778 0.5588)
			(end 1.3208 0.5588)
			(stroke
				(width 0.1524)
				(type default)
			)
			(layer "F.SilkS")
		)
		(fp_line
			(start -1.3208 -0.5588)
			(end 1.3208 -0.5588)
			(stroke
				(width 0.1524)
				(type default)
			)
			(layer "F.SilkS")
		)
		(fp_line
			(start 1.3208 -0.5588)
			(end 1.3208 0.5588)
			(stroke
				(width 0.1524)
				(type default)
			)
			(layer "F.SilkS")
		)
		(fp_line
			(start 1.4732 -0.5588)
			(end 1.4732 0.5588)
			(stroke
				(width 0.1524)
				(type default)
			)
			(layer "F.SilkS")
		)
		(fp_line
			(start 1.778 -0.5588)
			(end 1.778 0.5588)
			(stroke
				(width 0.1524)
				(type default)
			)
			(layer "F.SilkS")
		)
		(fp_line
			(start 1.778 -0.5588)
			(end 1.3208 -0.5588)
			(stroke
				(width 0.1524)
				(type default)
			)
			(layer "F.SilkS")
		)
		(fp_rect
			(start -1.1684 0.508)
			(end 1.1684 -0.508)
			(stroke
				(width 0)
				(type default)
			)
			(fill no)
			(layer "F.CrtYd")
		)
		(pad "A" smd rect
			(at -0.750062 0 270)
			(size 0.8128 0.8128)
			(layers "F.Cu" "F.Mask" "F.Paste")
			(net "UART_SW_S0_N")
		)
		(pad "C" smd rect
			(at 0.750062 0 270)
			(size 0.8128 0.8128)
			(layers "F.Cu" "F.Mask" "F.Paste")
			(net "N31328106")
		)
	)
	(footprint ""
		(layer "F.Cu")
		(at 153.541222 -91.32951 -90)
		(property "Reference" "R531"
			(at -0.411988 3.409188 0)
			(unlocked yes)
			(layer "F.SilkS")
			(effects
				(font
					(size 0.7874 0.5842)
					(thickness 0.1524)
				)
				(justify left)
			)
		)
		(property "Value" ""
			(at 0 0 270)
			(layer "F.Fab")
			(effects
				(font
					(size 1.27 1.27)
				)
			)
		)
		(duplicate_pad_numbers_are_jumpers no)
		(fp_line
			(start -0.7874 0.4064)
			(end -0.7874 -0.4064)
			(stroke
				(width 0.1524)
				(type default)
			)
			(layer "F.SilkS")
		)
		(fp_line
			(start 0.7874 0.4064)
			(end -0.7874 0.4064)
			(stroke
				(width 0.1524)
				(type default)
			)
			(layer "F.SilkS")
		)
		(fp_line
			(start -0.7874 -0.4064)
			(end 0.7874 -0.4064)
			(stroke
				(width 0.1524)
				(type default)
			)
			(layer "F.SilkS")
		)
		(fp_line
			(start 0.7874 -0.4064)
			(end 0.7874 0.4064)
			(stroke
				(width 0.1524)
				(type default)
			)
			(layer "F.SilkS")
		)
		(fp_poly
			(pts
				(xy -0.508 0.2794) (xy -0.508 0.2286) (xy -0.635 0.2286) (xy -0.635 -0.254) (xy -0.5334 -0.254)
				(xy -0.5334 -0.2794) (xy 0.5334 -0.2794) (xy 0.5334 -0.254) (xy 0.635 -0.254) (xy 0.635 0.254) (xy 0.5334 0.254)
				(xy 0.5334 0.2794)
			)
			(stroke
				(width 0)
				(type default)
			)
			(fill no)
			(layer "F.CrtYd")
		)
		(pad "1" smd rect
			(at 0.40005 0 270)
			(size 0.4572 0.508)
			(layers "F.Cu" "F.Mask" "F.Paste")
			(net "SPI_USB_NODE1_SI")
		)
		(pad "2" smd rect
			(at -0.40005 0 270)
			(size 0.4572 0.508)
			(layers "F.Cu" "F.Mask" "F.Paste")
			(net "P3V3_NODE1")
		)
	)
	(footprint ""
		(layer "F.Cu")
		(at 71.305166 -96.709992 90)
		(property "Reference" "R71"
			(at -54.98719 28.34005 90)
			(unlocked yes)
			(layer "F.SilkS")
			(effects
				(font
					(size 0.7874 0.5842)
					(thickness 0.1524)
				)
				(justify left)
			)
		)
		(property "Value" ""
			(at 0 0 90)
			(layer "F.Fab")
			(effects
				(font
					(size 1.27 1.27)
				)
			)
		)
		(duplicate_pad_numbers_are_jumpers no)
		(fp_line
			(start 0.7874 -0.4064)
			(end 0.7874 0.4064)
			(stroke
				(width 0.1524)
				(type default)
			)
			(layer "F.SilkS")
		)
		(fp_line
			(start -0.7874 -0.4064)
			(end 0.7874 -0.4064)
			(stroke
				(width 0.1524)
				(type default)
			)
			(layer "F.SilkS")
		)
		(fp_line
			(start 0.7874 0.4064)
			(end -0.7874 0.4064)
			(stroke
				(width 0.1524)
				(type default)
			)
			(layer "F.SilkS")
		)
		(fp_line
			(start -0.7874 0.4064)
			(end -0.7874 -0.4064)
			(stroke
				(width 0.1524)
				(type default)
			)
			(layer "F.SilkS")
		)
		(fp_poly
			(pts
				(xy -0.508 0.2794) (xy -0.508 0.2286) (xy -0.635 0.2286) (xy -0.635 -0.254) (xy -0.5334 -0.254)
				(xy -0.5334 -0.2794) (xy 0.5334 -0.2794) (xy 0.5334 -0.254) (xy 0.635 -0.254) (xy 0.635 0.254) (xy 0.5334 0.254)
				(xy 0.5334 0.2794)
			)
			(stroke
				(width 0)
				(type default)
			)
			(fill no)
			(layer "F.CrtYd")
		)
		(pad "1" smd rect
			(at 0.40005 0 90)
			(size 0.4572 0.508)
			(layers "F.Cu" "F.Mask" "F.Paste")
			(net "SPC_CPU_NODE1_RTS_L")
		)
		(pad "2" smd rect
			(at -0.40005 0 90)
			(size 0.4572 0.508)
			(layers "F.Cu" "F.Mask" "F.Paste")
			(net "SPC_CPU_NODE1_CTS_L")
		)
	)
	(footprint ""
		(layer "F.Cu")
		(at 21.30679 -59.146694 180)
		(property "Reference" "C509"
			(at -11.60399 -3.004566 0)
			(unlocked yes)
			(layer "F.SilkS")
			(effects
				(font
					(size 0.7874 0.5842)
					(thickness 0.1524)
				)
				(justify left)
			)
		)
		(property "Value" ""
			(at 0 0 180)
			(layer "F.Fab")
			(effects
				(font
					(size 1.27 1.27)
				)
			)
		)
		(duplicate_pad_numbers_are_jumpers no)
		(fp_line
			(start 0.7874 0.4064)
			(end -0.7874 0.4064)
			(stroke
				(width 0.1524)
				(type default)
			)
			(layer "F.SilkS")
		)
		(fp_line
			(start 0.7874 -0.4064)
			(end 0.7874 0.4064)
			(stroke
				(width 0.1524)
				(type default)
			)
			(layer "F.SilkS")
		)
		(fp_line
			(start 0 0.381)
			(end 0 -0.381)
			(stroke
				(width 0.1524)
				(type default)
			)
			(layer "F.SilkS")
		)
		(fp_line
			(start -0.7874 0.4064)
			(end -0.7874 -0.4064)
			(stroke
				(width 0.1524)
				(type default)
			)
			(layer "F.SilkS")
		)
		(fp_line
			(start -0.7874 -0.4064)
			(end 0.7874 -0.4064)
			(stroke
				(width 0.1524)
				(type default)
			)
			(layer "F.SilkS")
		)
		(fp_poly
			(pts
				(xy -0.5334 0.254) (xy -0.635 0.254) (xy -0.635 0.2286) (xy -0.635 -0.254) (xy -0.5334 -0.254) (xy -0.5334 -0.2794)
				(xy 0.5334 -0.2794) (xy 0.5334 -0.254) (xy 0.635 -0.254) (xy 0.635 0.254) (xy 0.5334 0.254) (xy 0.5334 0.2794)
				(xy -0.508 0.2794) (xy -0.5334 0.2794)
			)
			(stroke
				(width 0)
				(type default)
			)
			(fill no)
			(layer "F.CrtYd")
		)
		(pad "1" smd rect
			(at 0.40005 0 180)
			(size 0.4572 0.508)
			(layers "F.Cu" "F.Mask" "F.Paste")
			(net "GND")
		)
		(pad "2" smd rect
			(at -0.40005 0 180)
			(size 0.4572 0.508)
			(layers "F.Cu" "F.Mask" "F.Paste")
			(net "P5V_CRT")
		)
	)
)
